(kicad_pcb
	(version 20260206)
	(generator "pcbnew")
	(generator_version "10.0")
	(general
		(thickness 1.21888)
		(legacy_teardrops no)
	)
	(paper "A4")
	(title_block
		(title "timecard-v7 — TimeCard-DC-V7_EXP.PcbDoc")
		(comment 1 "Time Appliance Project (Time Card) / footprints 9-21 of 160")
	)
	(layers
		(0 "F.Cu" signal "TOP")
		(4 "In1.Cu" signal "SGND")
		(6 "In2.Cu" signal "IN1")
		(8 "In3.Cu" signal "IN2")
		(10 "In4.Cu" signal "SGND1")
		(2 "B.Cu" signal "BOTTOM")
		(9 "F.Adhes" user "F.Adhesive")
		(11 "B.Adhes" user "B.Adhesive")
		(13 "F.Paste" user "Top Paste")
		(15 "B.Paste" user "Bottom Paste")
		(5 "F.SilkS" user "Top Overlay")
		(7 "B.SilkS" user "Bottom Overlay")
		(1 "F.Mask" user "Top Solder")
		(3 "B.Mask" user "Bottom Solder")
		(17 "Dwgs.User" user "User.Drawings")
		(19 "Cmts.User" user "User.Comments")
		(21 "Eco1.User" user "User.Eco1")
		(23 "Eco2.User" user "User.Eco2")
		(25 "Edge.Cuts" user)
		(27 "Margin" user)
		(31 "F.CrtYd" user "Top Courtyard")
		(29 "B.CrtYd" user "Bottom Courtyard")
		(35 "F.Fab" user "Top Component Center")
		(33 "B.Fab" user "Bottom Component Center")
	)
	(footprint "Resistors:RESC1608X50N"
		(layer "F.Cu")
		(at 211.0605 110.9722 90)
		(property "Reference" "R4"
			(at -0.619 1.771345 90)
			(unlocked yes)
			(layer "F.SilkS")
			(effects
				(font
					(size 0.762 0.762)
					(thickness 0.2286)
				)
				(justify left bottom)
			)
		)
		(property "Value" "ERJ-3EKF4702V"
			(at -4.12259 1.7773 0)
			(unlocked yes)
			(layer "F.SilkS")
			(hide yes)
			(effects
				(font
					(size 1.524 1.524)
					(thickness 0.254)
				)
				(justify left bottom)
			)
		)
		(sheetname "POWER")
		(sheetfile "POWER.kicad_sch")
		(duplicate_pad_numbers_are_jumpers no)
		(fp_line
			(start 0 -0.5)
			(end 0 0.5)
			(stroke
				(width 0.1524)
				(type solid)
			)
			(layer "F.SilkS")
		)
		(pad "1" smd rect
			(at -0.69 0 180)
			(size 1 0.72)
			(layers "F.Cu" "F.Mask" "F.Paste")
			(net "+5.0V")
		)
		(pad "2" smd rect
			(at 0.69 0 180)
			(size 1 0.72)
			(layers "F.Cu" "F.Mask" "F.Paste")
			(net "NetR4_2")
		)
	)
	(footprint "Connectors:39-30-1060"
		(layer "F.Cu")
		(at 221.6261 96.1162 90)
		(property "Reference" "J38"
			(at -11.2 -2.006655 90)
			(unlocked yes)
			(layer "F.SilkS")
			(effects
				(font
					(size 0.762 0.762)
					(thickness 0.2286)
				)
				(justify left bottom)
			)
		)
		(property "Value" "39-30-1060"
			(at -20.89579 -1.5141 0)
			(unlocked yes)
			(layer "F.SilkS")
			(hide yes)
			(effects
				(font
					(size 1.524 1.524)
					(thickness 0.254)
				)
				(justify left bottom)
			)
		)
		(sheetname "POWER")
		(sheetfile "POWER.kicad_sch")
		(duplicate_pad_numbers_are_jumpers no)
		(fp_line
			(start 3.175 -1.524)
			(end 3.175 19.49249)
			(stroke
				(width 0.2032)
				(type solid)
			)
			(layer "F.SilkS")
		)
		(fp_line
			(start -11.02502 -1.524)
			(end 3.175 -1.524)
			(stroke
				(width 0.2032)
				(type solid)
			)
			(layer "F.SilkS")
		)
		(fp_line
			(start -11.02502 -1.51445)
			(end -11.02502 -0.44249)
			(stroke
				(width 0.203)
				(type solid)
			)
			(layer "F.SilkS")
		)
		(fp_line
			(start -11.02502 -0.44249)
			(end -11.02502 19.49249)
			(stroke
				(width 0.2032)
				(type solid)
			)
			(layer "F.SilkS")
		)
		(pad "" np_thru_hole circle
			(at -8.4 12.8 90)
			(size 1.27 1.27)
			(drill 3)
			(layers "*.Cu" "*.Mask")
			(thermal_bridge_angle 90)
		)
		(pad "" np_thru_hole circle
			(at 0 12.8 90)
			(size 1.27 1.27)
			(drill 3)
			(layers "*.Cu" "*.Mask")
			(thermal_bridge_angle 90)
			(padstack
				(mode front_inner_back)
				(layer "Inner"
					(shape circle)
					(size 1.27 1.27)
				)
				(layer "B.Cu"
					(shape circle)
					(size 1.27 1.27)
				)
			)
		)
		(pad "1" thru_hole circle
			(at 0 5.5 180)
			(size 2.5 2.5)
			(drill 1.8)
			(layers "*.Cu" "*.Mask")
			(remove_unused_layers no)
			(net "NetD12_2")
			(thermal_bridge_angle 90)
		)
		(pad "2" thru_hole circle
			(at -4.2 5.5 180)
			(size 2.5 2.5)
			(drill 1.8)
			(layers "*.Cu" "*.Mask")
			(remove_unused_layers no)
			(net "NetD12_2")
			(thermal_bridge_angle 90)
		)
		(pad "3" thru_hole circle
			(at -8.4 5.5 180)
			(size 2.5 2.5)
			(drill 1.8)
			(layers "*.Cu" "*.Mask")
			(remove_unused_layers no)
			(net "NetD12_2")
			(thermal_bridge_angle 90)
		)
		(pad "4" thru_hole circle
			(at 0 0 180)
			(size 2.5 2.5)
			(drill 1.8)
			(layers "*.Cu" "*.Mask")
			(remove_unused_layers no)
			(net "GND")
			(thermal_bridge_angle 90)
		)
		(pad "5" thru_hole circle
			(at -4.2 0 180)
			(size 2.5 2.5)
			(drill 1.8)
			(layers "*.Cu" "*.Mask")
			(remove_unused_layers no)
			(net "GND")
			(thermal_bridge_angle 90)
		)
		(pad "6" thru_hole circle
			(at -8.4 0 180)
			(size 2.5 2.5)
			(drill 1.8)
			(layers "*.Cu" "*.Mask")
			(remove_unused_layers no)
			(net "GND")
			(thermal_bridge_angle 90)
		)
	)
	(footprint "IntegratedCircuits:SOIC127P600X175-8N"
		(layer "F.Cu")
		(at 205.1917 88.2392 90)
		(property "Reference" "U2"
			(at 6.13379 -2.264865 270)
			(unlocked yes)
			(layer "F.SilkS")
			(effects
				(font
					(size 0.762 0.762)
					(thickness 0.2286)
				)
				(justify left bottom)
			)
		)
		(property "Value" "MP1482DS-LF"
			(at -9.52079 10.9955 0)
			(unlocked yes)
			(layer "F.SilkS")
			(hide yes)
			(effects
				(font
					(size 1.524 1.524)
					(thickness 0.254)
				)
				(justify left bottom)
			)
		)
		(sheetname "POWER")
		(sheetfile "POWER.kicad_sch")
		(duplicate_pad_numbers_are_jumpers no)
		(fp_line
			(start -3.4 -2.5)
			(end 2 -2.5)
			(stroke
				(width 0.12)
				(type solid)
			)
			(layer "F.SilkS")
		)
		(fp_line
			(start -2 2.5)
			(end 2 2.5)
			(stroke
				(width 0.12)
				(type solid)
			)
			(layer "F.SilkS")
		)
		(pad "1" smd rect
			(at -2.475 -1.905 90)
			(size 1.97 0.57)
			(layers "F.Cu" "F.Mask" "F.Paste")
			(net "NetC3_1")
		)
		(pad "2" smd rect
			(at -2.475 -0.635 90)
			(size 1.97 0.57)
			(layers "F.Cu" "F.Mask" "F.Paste")
			(net "+12V")
		)
		(pad "3" smd rect
			(at -2.475 0.635 90)
			(size 1.97 0.57)
			(layers "F.Cu" "F.Mask" "F.Paste")
			(net "NetC3_2")
		)
		(pad "4" smd rect
			(at -2.475 1.905 90)
			(size 1.97 0.57)
			(layers "F.Cu" "F.Mask" "F.Paste")
			(net "GND")
		)
		(pad "5" smd rect
			(at 2.475 1.905 90)
			(size 1.97 0.57)
			(layers "F.Cu" "F.Mask" "F.Paste")
			(net "NetR5_1")
		)
		(pad "6" smd rect
			(at 2.475 0.635 90)
			(size 1.97 0.57)
			(layers "F.Cu" "F.Mask" "F.Paste")
			(net "NetC22_2")
		)
		(pad "7" smd rect
			(at 2.475 -0.635 90)
			(size 1.97 0.57)
			(layers "F.Cu" "F.Mask" "F.Paste")
			(net "NetR3_1")
		)
		(pad "8" smd rect
			(at 2.475 -1.905 90)
			(size 1.97 0.57)
			(layers "F.Cu" "F.Mask" "F.Paste")
			(net "NetC21_2")
		)
	)
	(footprint "Vault:RESC1608X55X30NL15T15"
		(layer "F.Cu")
		(at 73.3761 55.6162 90)
		(property "Reference" "R38"
			(at -5.7714 0.026921 90)
			(unlocked yes)
			(layer "F.SilkS")
			(effects
				(font
					(size 0.762 0.762)
					(thickness 0.2286)
				)
			)
		)
		(property "Value" "200 OHM"
			(at -2.962402 4.81166 0)
			(unlocked yes)
			(layer "F.SilkS")
			(hide yes)
			(effects
				(font
					(size 1.524 1.524)
					(thickness 0.254)
				)
			)
		)
		(sheetname "USER_IO_STATUS")
		(sheetfile "USER_IO_STATUS.kicad_sch")
		(duplicate_pad_numbers_are_jumpers no)
		(pad "1" smd rect
			(at -0.675 0 180)
			(size 0.95 0.8)
			(layers "F.Cu" "F.Mask" "F.Paste")
			(net "LED3")
		)
		(pad "2" smd rect
			(at 0.675 0 180)
			(size 0.95 0.8)
			(layers "F.Cu" "F.Mask" "F.Paste")
			(net "NetD10_1")
		)
	)
	(footprint "Vault:RESC1609X50X30NL10T20"
		(layer "F.Cu")
		(at 113.8761 84.8286 -90)
		(property "Reference" "R12"
			(at 2.2714 -0.026931 90)
			(unlocked yes)
			(layer "F.SilkS")
			(effects
				(font
					(size 0.762 0.762)
					(thickness 0.2286)
				)
			)
		)
		(property "Value" "110R"
			(at -2.911602 2.27248 180)
			(unlocked yes)
			(layer "F.SilkS")
			(hide yes)
			(effects
				(font
					(size 1.524 1.524)
					(thickness 0.254)
				)
			)
		)
		(sheetname "MAC")
		(sheetfile "MAC.kicad_sch")
		(duplicate_pad_numbers_are_jumpers no)
		(pad "1" smd rect
			(at -0.625 0)
			(size 0.95 0.8)
			(layers "F.Cu" "F.Mask" "F.Paste")
			(net "MAC_PPS_OUT-")
		)
		(pad "2" smd rect
			(at 0.625 0)
			(size 0.95 0.8)
			(layers "F.Cu" "F.Mask" "F.Paste")
			(net "MAC_PPS_OUT+")
		)
	)
	(footprint "Capacitors:CAPC2012X14N"
		(layer "F.Cu")
		(at 200.8737 90.2712 180)
		(property "Reference" "C5"
			(at 3.41 -0.488345 0)
			(unlocked yes)
			(layer "F.SilkS")
			(effects
				(font
					(size 0.762 0.762)
					(thickness 0.2286)
				)
				(justify left bottom)
			)
		)
		(property "Value" "CAP_0805_10UF_25V"
			(at -15.2119 -1.41819 0)
			(unlocked yes)
			(layer "F.SilkS")
			(hide yes)
			(effects
				(font
					(size 1.524 1.524)
					(thickness 0.254)
				)
				(justify left bottom)
			)
		)
		(sheetname "POWER")
		(sheetfile "POWER.kicad_sch")
		(duplicate_pad_numbers_are_jumpers no)
		(fp_line
			(start 0.762 0.9652)
			(end -0.762 0.9652)
			(stroke
				(width 0.1524)
				(type solid)
			)
			(layer "F.SilkS")
		)
		(fp_line
			(start 0.762 -0.9652)
			(end -0.762 -0.9652)
			(stroke
				(width 0.1524)
				(type solid)
			)
			(layer "F.SilkS")
		)
		(pad "1" smd rect
			(at -0.9 0 270)
			(size 1.45 1.15)
			(layers "F.Cu" "F.Mask" "F.Paste")
			(net "+12V")
		)
		(pad "2" smd rect
			(at 0.9 0 270)
			(size 1.45 1.15)
			(layers "F.Cu" "F.Mask" "F.Paste")
			(net "GND")
		)
	)
	(footprint "Capacitors:CAPC2012X14N"
		(layer "F.Cu")
		(at 218.2995 116.1792 -90)
		(property "Reference" "C14"
			(at -1.97531 -1.604455 90)
			(unlocked yes)
			(layer "F.SilkS")
			(effects
				(font
					(size 0.762 0.762)
					(thickness 0.2286)
				)
				(justify left bottom)
			)
		)
		(property "Value" "CAP_0805_10UF_25V"
			(at 6.89119 10.8719 0)
			(unlocked yes)
			(layer "F.SilkS")
			(hide yes)
			(effects
				(font
					(size 1.524 1.524)
					(thickness 0.254)
				)
				(justify left bottom)
			)
		)
		(sheetname "POWER")
		(sheetfile "POWER.kicad_sch")
		(duplicate_pad_numbers_are_jumpers no)
		(fp_line
			(start 0.762 0.9652)
			(end -0.762 0.9652)
			(stroke
				(width 0.1524)
				(type solid)
			)
			(layer "F.SilkS")
		)
		(fp_line
			(start 0.762 -0.9652)
			(end -0.762 -0.9652)
			(stroke
				(width 0.1524)
				(type solid)
			)
			(layer "F.SilkS")
		)
		(pad "1" smd rect
			(at -0.9 0)
			(size 1.45 1.15)
			(layers "F.Cu" "F.Mask" "F.Paste")
			(net "+5.0V")
		)
		(pad "2" smd rect
			(at 0.9 0)
			(size 1.45 1.15)
			(layers "F.Cu" "F.Mask" "F.Paste")
			(net "GND")
		)
	)
	(footprint "Vault:CAPC1608X87X45ML20T05"
		(layer "F.Cu")
		(at 212.5637 90.4662 90)
		(property "Reference" "C11"
			(at 4.1 0.606655 270)
			(unlocked yes)
			(layer "F.SilkS")
			(effects
				(font
					(size 0.762 0.762)
					(thickness 0.2286)
				)
				(justify left bottom)
			)
		)
		(property "Value" "0.1uF"
			(at -10.31039 4.5043 0)
			(unlocked yes)
			(layer "F.SilkS")
			(hide yes)
			(effects
				(font
					(size 1.524 1.524)
					(thickness 0.254)
				)
				(justify left bottom)
			)
		)
		(sheetname "POWER")
		(sheetfile "POWER.kicad_sch")
		(duplicate_pad_numbers_are_jumpers no)
		(pad "1" smd rect
			(at -0.7 0 180)
			(size 1.1 1.05)
			(layers "F.Cu" "F.Mask" "F.Paste")
			(net "GND")
		)
		(pad "2" smd rect
			(at 0.7 0 180)
			(size 1.1 1.05)
			(layers "F.Cu" "F.Mask" "F.Paste")
			(net "+3.3V")
		)
	)
	(footprint "Vault:RESC1608X55X30NL15T15"
		(layer "F.Cu")
		(at 71.6261 55.6162 90)
		(property "Reference" "R36"
			(at -5.7714 -0.223079 90)
			(unlocked yes)
			(layer "F.SilkS")
			(effects
				(font
					(size 0.762 0.762)
					(thickness 0.2286)
				)
			)
		)
		(property "Value" "200 OHM"
			(at -2.962402 4.81166 0)
			(unlocked yes)
			(layer "F.SilkS")
			(hide yes)
			(effects
				(font
					(size 1.524 1.524)
					(thickness 0.254)
				)
			)
		)
		(sheetname "USER_IO_STATUS")
		(sheetfile "USER_IO_STATUS.kicad_sch")
		(duplicate_pad_numbers_are_jumpers no)
		(pad "1" smd rect
			(at -0.675 0 180)
			(size 0.95 0.8)
			(layers "F.Cu" "F.Mask" "F.Paste")
			(net "LED2")
		)
		(pad "2" smd rect
			(at 0.675 0 180)
			(size 0.95 0.8)
			(layers "F.Cu" "F.Mask" "F.Paste")
			(net "NetD9_1")
		)
	)
	(footprint "Vault:AMPH-901-143-6RFX_V"
		(layer "F.Cu")
		(at 60.9761 122.0782 180)
		(property "Reference" "AN3"
			(at -5.917345 2.516 90)
			(unlocked yes)
			(layer "F.SilkS")
			(effects
				(font
					(size 0.762 0.762)
					(thickness 0.2286)
				)
				(justify left bottom)
			)
		)
		(property "Value" "901-143-6RFX"
			(at 4.6101 -2.05359 0)
			(unlocked yes)
			(layer "F.SilkS")
			(hide yes)
			(effects
				(font
					(size 1.524 1.524)
					(thickness 0.254)
				)
				(justify left bottom)
			)
		)
		(sheetname "USER_IO")
		(sheetfile "USER_IO.kicad_sch")
		(duplicate_pad_numbers_are_jumpers no)
		(fp_line
			(start 3.5 -1.38)
			(end 3.5 1.38)
			(stroke
				(width 0.2)
				(type solid)
			)
			(layer "F.SilkS")
		)
		(fp_line
			(start 1.38 3.5)
			(end -1.38 3.5)
			(stroke
				(width 0.2)
				(type solid)
			)
			(layer "F.SilkS")
		)
		(fp_line
			(start 1.38 -3.5)
			(end -1.38 -3.5)
			(stroke
				(width 0.2)
				(type solid)
			)
			(layer "F.SilkS")
		)
		(fp_line
			(start -3.5 -1.38)
			(end -3.5 1.38)
			(stroke
				(width 0.2)
				(type solid)
			)
			(layer "F.SilkS")
		)
		(pad "1" thru_hole rect
			(at 0 0 180)
			(size 2 2)
			(drill 1.5)
			(layers "*.Cu" "*.Mask")
			(remove_unused_layers no)
			(net "NetAN3_1")
		)
		(pad "2" thru_hole circle
			(at -2.54 -2.54 180)
			(size 2.2 2.2)
			(drill 1.7)
			(layers "*.Cu" "*.Mask")
			(remove_unused_layers no)
			(net "GND")
			(thermal_bridge_angle 90)
		)
		(pad "3" thru_hole circle
			(at -2.54 2.54 180)
			(size 2.2 2.2)
			(drill 1.7)
			(layers "*.Cu" "*.Mask")
			(remove_unused_layers no)
			(net "GND")
			(thermal_bridge_angle 90)
		)
		(pad "4" thru_hole circle
			(at 2.54 2.54 180)
			(size 2.2 2.2)
			(drill 1.7)
			(layers "*.Cu" "*.Mask")
			(remove_unused_layers no)
			(net "GND")
			(thermal_bridge_angle 90)
		)
		(pad "5" thru_hole circle
			(at 2.54 -2.54 180)
			(size 2.2 2.2)
			(drill 1.7)
			(layers "*.Cu" "*.Mask")
			(remove_unused_layers no)
			(net "GND")
			(thermal_bridge_angle 90)
		)
	)
	(footprint "Vault:RESC1608X55X30NL15T15"
		(layer "F.Cu")
		(at 84.1261 112.1162 -90)
		(property "Reference" "R29"
			(at 4 -0.593345 90)
			(unlocked yes)
			(layer "F.SilkS")
			(effects
				(font
					(size 0.762 0.762)
					(thickness 0.2286)
				)
				(justify left bottom)
			)
		)
		(property "Value" "4.7K"
			(at 3.72999 0.4445 0)
			(unlocked yes)
			(layer "F.SilkS")
			(hide yes)
			(effects
				(font
					(size 1.524 1.524)
					(thickness 0.254)
				)
				(justify left bottom)
			)
		)
		(sheetname "USER_IO")
		(sheetfile "USER_IO.kicad_sch")
		(duplicate_pad_numbers_are_jumpers no)
		(pad "1" smd rect
			(at -0.75 0)
			(size 0.95 0.95)
			(layers "F.Cu" "F.Mask" "F.Paste")
			(net "ANT2_IO_OUT")
		)
		(pad "2" smd rect
			(at 0.75 0)
			(size 0.95 0.95)
			(layers "F.Cu" "F.Mask" "F.Paste")
			(net "+3.3V")
		)
	)
	(footprint "GNSS:GNSS"
		(locked yes)
		(layer "F.Cu")
		(at 225.8486 61.6786 180)
		(property "Reference" "U15"
			(at 62.698119 -18.19972 90)
			(unlocked yes)
			(layer "F.SilkS")
			(effects
				(font
					(size 0.762 0.762)
					(thickness 0.2286)
				)
			)
		)
		(property "Value" "RCB-F9T-1"
			(at -7.813802 -13.730755 90)
			(unlocked yes)
			(layer "F.SilkS")
			(hide yes)
			(effects
				(font
					(size 1.524 1.524)
					(thickness 0.254)
				)
			)
		)
		(sheetname "GPS_IMU_SENSORS")
		(sheetfile "GPS_IMU_SENSORS.kicad_sch")
		(duplicate_pad_numbers_are_jumpers no)
		(fp_line
			(start 61.07 11.28)
			(end -6.11 11.28)
			(stroke
				(width 0.254)
				(type solid)
			)
			(layer "F.SilkS")
		)
		(fp_line
			(start 61.07 -20.47)
			(end 61.07 11.28)
			(stroke
				(width 0.254)
				(type solid)
			)
			(layer "F.SilkS")
		)
		(fp_line
			(start 61.07 -20.47)
			(end -6.11 -20.47)
			(stroke
				(width 0.254)
				(type solid)
			)
			(layer "F.SilkS")
		)
		(fp_line
			(start -6.11 -20.47)
			(end -6.11 11.28)
			(stroke
				(width 0.254)
				(type solid)
			)
			(layer "F.SilkS")
		)
		(pad "0" thru_hole circle
			(at 0 -2 90)
			(size 0 0)
			(drill 0.76)
			(layers "*.Cu" "*.Mask")
			(remove_unused_layers no)
			(thermal_bridge_angle 90)
		)
		(pad "0" thru_hole circle
			(at 0 2 90)
			(size 0 0)
			(drill 0.76)
			(layers "*.Cu" "*.Mask")
			(remove_unused_layers no)
			(thermal_bridge_angle 90)
		)
		(pad "1" smd rect
			(at -2.2225 3 90)
			(size 1.12 2.105)
			(layers "F.Cu" "F.Mask" "F.Paste")
			(net "+5.0V")
		)
		(pad "2" smd rect
			(at 2.2225 3 90)
			(size 1.12 2.105)
			(layers "F.Cu" "F.Mask" "F.Paste")
			(net "+3.3V")
		)
		(pad "3" smd rect
			(at -2.2225 1 90)
			(size 1.12 2.105)
			(layers "F.Cu" "F.Mask" "F.Paste")
			(net "GPS2_TX")
		)
		(pad "4" smd rect
			(at 2.2225 1 90)
			(size 1.12 2.105)
			(layers "F.Cu" "F.Mask" "F.Paste")
			(net "GPS2_RST")
		)
		(pad "5" smd rect
			(at -2.2225 -1 90)
			(size 1.12 2.105)
			(layers "F.Cu" "F.Mask" "F.Paste")
			(net "GPS2_RX")
		)
		(pad "6" smd rect
			(at 2.2225 -1 90)
			(size 1.12 2.105)
			(layers "F.Cu" "F.Mask" "F.Paste")
			(net "GPS2_TP1")
		)
		(pad "7" smd rect
			(at -2.2225 -3 90)
			(size 1.12 2.105)
			(layers "F.Cu" "F.Mask" "F.Paste")
			(net "GPS2_TP2")
		)
		(pad "8" smd rect
			(at 2.2225 -3 90)
			(size 1.12 2.105)
			(layers "F.Cu" "F.Mask" "F.Paste")
			(net "GND")
		)
	)
	(footprint "Resistors:RESC1608X50N"
		(layer "F.Cu")
		(at 208.8747 84.8864)
		(property "Reference" "R5"
			(at 1.639 0.398145 0)
			(unlocked yes)
			(layer "F.SilkS")
			(effects
				(font
					(size 0.762 0.762)
					(thickness 0.2286)
				)
				(justify left bottom)
			)
		)
		(property "Value" "ERJ-3EKF2612V"
			(at -9.7817 21.05239 0)
			(unlocked yes)
			(layer "F.SilkS")
			(hide yes)
			(effects
				(font
					(size 1.524 1.524)
					(thickness 0.254)
				)
				(justify left bottom)
			)
		)
		(sheetname "POWER")
		(sheetfile "POWER.kicad_sch")
		(duplicate_pad_numbers_are_jumpers no)
		(fp_line
			(start 0 0.5)
			(end 0 -0.5)
			(stroke
				(width 0.1524)
				(type solid)
			)
			(layer "F.SilkS")
		)
		(pad "1" smd rect
			(at -0.69 0 90)
			(size 1 0.72)
			(layers "F.Cu" "F.Mask" "F.Paste")
			(net "NetR5_1")
		)
		(pad "2" smd rect
			(at 0.69 0 90)
			(size 1 0.72)
			(layers "F.Cu" "F.Mask" "F.Paste")
			(net "+3.3V")
		)
	)
)
